# S9S_MB_2U (Grand Teton) — schematic netlist excerpt (pin names and nets, part order shuffled) for the footprints in the layout excerpt that follows; sources: Cadence DE-HDL packaged netlist, KiCad conversion of 03242023_DA0F0TMBIJ0_F0T_Motherboard_J_brd_V01_OCP.brd

C578  Q_CAP  0.1UF 25V 10% X7R  pkg 0402  page 158 : A = P3V3_AUX ; B = GND
R2969  Q_RES  0 5% CHIP  pkg 0402LF  page 128 : A = RST_CPU1_DRAM_GH_N ; B = RST_CPU1_DRAM_GH_PLD_N

(kicad_pcb
	(version 20260206)
	(generator "pcbnew")
	(generator_version "10.0")
	(general
		(thickness 1.6)
		(legacy_teardrops no)
	)
	(paper "A4")
	(title_block
		(title "03242023_DA0F0TMBIJ0_F0T_Motherboard_J_brd_V01_OCP.brd")
		(comment 1 "Grand Teton / footprints 2112-2113 of 6105")
	)
	(layers
		(0 "F.Cu" signal "TOP")
		(4 "In1.Cu" signal "GND")
		(6 "In2.Cu" signal "IN1")
		(8 "In3.Cu" signal "GND1")
		(10 "In4.Cu" signal "IN2")
		(12 "In5.Cu" signal "GND2")
		(14 "In6.Cu" signal "IN3")
		(16 "In7.Cu" signal "GND3")
		(18 "In8.Cu" signal "VCC")
		(20 "In9.Cu" signal "VCC1")
		(22 "In10.Cu" signal "GND4")
		(24 "In11.Cu" signal "IN4")
		(26 "In12.Cu" signal "GND5")
		(28 "In13.Cu" signal "IN5")
		(30 "In14.Cu" signal "GND6")
		(32 "In15.Cu" signal "IN6")
		(34 "In16.Cu" signal "GND7")
		(2 "B.Cu" signal "BOTTOM")
		(9 "F.Adhes" user "F.Adhesive")
		(11 "B.Adhes" user "B.Adhesive")
		(13 "F.Paste" user "Package Geometry/Pastemask Top")
		(15 "B.Paste" user "Package Geometry/Pastemask Bottom")
		(5 "F.SilkS" user "Ref Des/Silkscreen Top")
		(7 "B.SilkS" user "Ref Des/Silkscreen Bottom")
		(1 "F.Mask" user "Board Geometry/Soldermask Top")
		(3 "B.Mask" user "Board Geometry/Soldermask Bottom")
		(17 "Dwgs.User" user "User.Drawings")
		(19 "Cmts.User" user "User.Comments")
		(21 "Eco1.User" user "User.Eco1")
		(23 "Eco2.User" user "User.Eco2")
		(25 "Edge.Cuts" user "Board Geometry/Outline")
		(27 "Margin" user)
		(31 "F.CrtYd" user "Package Geometry/Place Bound Top")
		(29 "B.CrtYd" user "Package Geometry/Place Bound Bottom")
		(35 "F.Fab" user "Ref Des/Assembly Top")
		(33 "B.Fab" user "Ref Des/Assembly Bottom")
	)
	(footprint ""
		(layer "F.Cu")
		(at 451.81774 -113.172748 -90)
		(property "Reference" "C578"
			(at 0 0 270)
			(layer "F.SilkS")
			(hide yes)
			(effects
				(font
					(size 1.27 1.27)
				)
			)
		)
		(property "Value" ""
			(at 0 0 270)
			(layer "F.Fab")
			(effects
				(font
					(size 1.27 1.27)
				)
			)
		)
		(duplicate_pad_numbers_are_jumpers no)
		(fp_line
			(start -0.7874 0.4064)
			(end -0.7874 -0.4064)
			(stroke
				(width 0.1524)
				(type default)
			)
			(layer "F.SilkS")
		)
		(fp_line
			(start 0.7874 0.4064)
			(end -0.7874 0.4064)
			(stroke
				(width 0.1524)
				(type default)
			)
			(layer "F.SilkS")
		)
		(fp_line
			(start -0.7874 -0.4064)
			(end 0.7874 -0.4064)
			(stroke
				(width 0.1524)
				(type default)
			)
			(layer "F.SilkS")
		)
		(fp_line
			(start 0.7874 -0.4064)
			(end 0.7874 0.4064)
			(stroke
				(width 0.1524)
				(type default)
			)
			(layer "F.SilkS")
		)
		(fp_line
			(start -0.67945 0.3048)
			(end -0.67945 -0.305054)
			(stroke
				(width 0.1)
				(type default)
			)
			(layer "F.Fab")
		)
		(fp_line
			(start -0.12065 0.3048)
			(end -0.67945 0.3048)
			(stroke
				(width 0.1)
				(type default)
			)
			(layer "F.Fab")
		)
		(fp_line
			(start 0.120396 0.3048)
			(end 0.120396 0.2794)
			(stroke
				(width 0.1)
				(type default)
			)
			(layer "F.Fab")
		)
		(fp_line
			(start 0.67945 0.3048)
			(end 0.120396 0.3048)
			(stroke
				(width 0.1)
				(type default)
			)
			(layer "F.Fab")
		)
		(fp_line
			(start -0.12065 0.2794)
			(end -0.12065 0.3048)
			(stroke
				(width 0.1)
				(type default)
			)
			(layer "F.Fab")
		)
		(fp_line
			(start 0.120396 0.2794)
			(end -0.12065 0.2794)
			(stroke
				(width 0.1)
				(type default)
			)
			(layer "F.Fab")
		)
		(fp_line
			(start -0.12065 -0.2794)
			(end 0.12065 -0.2794)
			(stroke
				(width 0.1)
				(type default)
			)
			(layer "F.Fab")
		)
		(fp_line
			(start 0.12065 -0.2794)
			(end 0.12065 -0.3048)
			(stroke
				(width 0.1)
				(type default)
			)
			(layer "F.Fab")
		)
		(fp_line
			(start 0.12065 -0.3048)
			(end 0.67945 -0.3048)
			(stroke
				(width 0.1)
				(type default)
			)
			(layer "F.Fab")
		)
		(fp_line
			(start 0.67945 -0.3048)
			(end 0.67945 0.3048)
			(stroke
				(width 0.1)
				(type default)
			)
			(layer "F.Fab")
		)
		(fp_line
			(start -0.67945 -0.305054)
			(end -0.12065 -0.305054)
			(stroke
				(width 0.1)
				(type default)
			)
			(layer "F.Fab")
		)
		(fp_line
			(start -0.12065 -0.305054)
			(end -0.12065 -0.2794)
			(stroke
				(width 0.1)
				(type default)
			)
			(layer "F.Fab")
		)
		(pad "1" smd circle
			(at -0.40005 0 270)
			(size 0 0)
			(layers "F.Cu" "F.Mask" "F.Paste")
			(net "P3V3_AUX")
		)
		(pad "2" smd circle
			(at 0.40005 0 270)
			(size 0 0)
			(layers "F.Cu" "F.Mask" "F.Paste")
			(net "GND")
		)
	)
	(footprint ""
		(layer "F.Cu")
		(at 126.534926 -119.810784 -90)
		(property "Reference" "R2969"
			(at 0 0 270)
			(layer "F.SilkS")
			(hide yes)
			(effects
				(font
					(size 1.27 1.27)
				)
			)
		)
		(property "Value" ""
			(at 0 0 270)
			(layer "F.Fab")
			(effects
				(font
					(size 1.27 1.27)
				)
			)
		)
		(duplicate_pad_numbers_are_jumpers no)
		(fp_line
			(start -0.7874 0.4064)
			(end -0.7874 -0.4064)
			(stroke
				(width 0.1524)
				(type default)
			)
			(layer "F.SilkS")
		)
		(fp_line
			(start 0.7874 0.4064)
			(end -0.7874 0.4064)
			(stroke
				(width 0.1524)
				(type default)
			)
			(layer "F.SilkS")
		)
		(fp_line
			(start -0.7874 -0.4064)
			(end 0.7874 -0.4064)
			(stroke
				(width 0.1524)
				(type default)
			)
			(layer "F.SilkS")
		)
		(fp_line
			(start 0.7874 -0.4064)
			(end 0.7874 0.4064)
			(stroke
				(width 0.1524)
				(type default)
			)
			(layer "F.SilkS")
		)
		(fp_line
			(start -0.67945 0.3048)
			(end -0.67945 -0.305054)
			(stroke
				(width 0.1)
				(type default)
			)
			(layer "F.Fab")
		)
		(fp_line
			(start -0.12065 0.3048)
			(end -0.67945 0.3048)
			(stroke
				(width 0.1)
				(type default)
			)
			(layer "F.Fab")
		)
		(fp_line
			(start 0.120396 0.3048)
			(end 0.120396 0.2794)
			(stroke
				(width 0.1)
				(type default)
			)
			(layer "F.Fab")
		)
		(fp_line
			(start 0.67945 0.3048)
			(end 0.120396 0.3048)
			(stroke
				(width 0.1)
				(type default)
			)
			(layer "F.Fab")
		)
		(fp_line
			(start -0.12065 0.2794)
			(end -0.12065 0.3048)
			(stroke
				(width 0.1)
				(type default)
			)
			(layer "F.Fab")
		)
		(fp_line
			(start 0.120396 0.2794)
			(end -0.12065 0.2794)
			(stroke
				(width 0.1)
				(type default)
			)
			(layer "F.Fab")
		)
		(fp_line
			(start -0.12065 -0.2794)
			(end 0.12065 -0.2794)
			(stroke
				(width 0.1)
				(type default)
			)
			(layer "F.Fab")
		)
		(fp_line
			(start 0.12065 -0.2794)
			(end 0.12065 -0.3048)
			(stroke
				(width 0.1)
				(type default)
			)
			(layer "F.Fab")
		)
		(fp_line
			(start 0.12065 -0.3048)
			(end 0.67945 -0.3048)
			(stroke
				(width 0.1)
				(type default)
			)
			(layer "F.Fab")
		)
		(fp_line
			(start 0.67945 -0.3048)
			(end 0.67945 0.3048)
			(stroke
				(width 0.1)
				(type default)
			)
			(layer "F.Fab")
		)
		(fp_line
			(start -0.67945 -0.305054)
			(end -0.12065 -0.305054)
			(stroke
				(width 0.1)
				(type default)
			)
			(layer "F.Fab")
		)
		(fp_line
			(start -0.12065 -0.305054)
			(end -0.12065 -0.2794)
			(stroke
				(width 0.1)
				(type default)
			)
			(layer "F.Fab")
		)
		(pad "1" smd circle
			(at -0.40005 0 270)
			(size 0 0)
			(layers "F.Cu" "F.Mask" "F.Paste")
			(net "RST_CPU1_DRAM_GH_N")
		)
		(pad "2" smd circle
			(at 0.40005 0 270)
			(size 0 0)
			(layers "F.Cu" "F.Mask" "F.Paste")
			(net "RST_CPU1_DRAM_GH_PLD_N")
		)
	)
)
